(kicad_pcb
	(version 20260206)
	(generator "pcbnew")
	(generator_version "10.0")
	(general
		(thickness 1.6)
		(legacy_teardrops no)
	)
	(paper "A4")
	(title_block
		(title "Bryce Canyon_F.DPB_16315-1-OCP.brd")
		(comment 1 "Bryce Canyon / footprints 773-779 of 2223")
	)
	(layers
		(0 "F.Cu" signal "TOP")
		(4 "In1.Cu" signal "L2GND")
		(6 "In2.Cu" signal "L3")
		(8 "In3.Cu" signal "L4GND")
		(10 "In4.Cu" signal "L5")
		(12 "In5.Cu" signal "L6VCC")
		(14 "In6.Cu" signal "L7VCC")
		(16 "In7.Cu" signal "L8")
		(18 "In8.Cu" signal "L9GND")
		(20 "In9.Cu" signal "L10")
		(22 "In10.Cu" signal "L11GND")
		(2 "B.Cu" signal "BOTTOM")
		(9 "F.Adhes" user "F.Adhesive")
		(11 "B.Adhes" user "B.Adhesive")
		(13 "F.Paste" user "Package Geometry/Pastemask Top")
		(15 "B.Paste" user "Package Geometry/Pastemask Bottom")
		(5 "F.SilkS" user "Ref Des/Silkscreen Top")
		(7 "B.SilkS" user "Ref Des/Silkscreen Bottom")
		(1 "F.Mask" user "Board Geometry/Soldermask Top")
		(3 "B.Mask" user "Board Geometry/Soldermask Bottom")
		(17 "Dwgs.User" user "User.Drawings")
		(19 "Cmts.User" user "User.Comments")
		(21 "Eco1.User" user "User.Eco1")
		(23 "Eco2.User" user "User.Eco2")
		(25 "Edge.Cuts" user "Board Geometry/Outline")
		(27 "Margin" user)
		(31 "F.CrtYd" user "Package Geometry/Place Bound Top")
		(29 "B.CrtYd" user "Package Geometry/Place Bound Bottom")
		(35 "F.Fab" user "Ref Des/Assembly Top")
		(33 "B.Fab" user "Ref Des/Assembly Bottom")
	)
	(footprint ""
		(layer "F.Cu")
		(at 220.588332 -389.492998 180)
		(property "Reference" "Q22"
			(at 0 0 180)
			(layer "F.SilkS")
			(hide yes)
			(effects
				(font
					(size 1.27 1.27)
				)
			)
		)
		(property "Value" "2N7002K-1-GP"
			(at 0.127 -8.9662 180)
			(unlocked yes)
			(layer "F.Fab")
			(hide yes)
			(effects
				(font
					(size 1.016 1.016)
					(thickness 0.1524)
				)
			)
		)
		(property "Device Type" "SOT23DGS2D4H44"
			(at 0.127 -10.4902 180)
			(unlocked yes)
			(layer "F.Fab")
			(hide yes)
			(effects
				(font
					(size 1.016 1.016)
					(thickness 0.1524)
				)
			)
		)
		(duplicate_pad_numbers_are_jumpers no)
		(fp_line
			(start 1.651 1.778)
			(end 1.651 -1.778)
			(stroke
				(width 0.1524)
				(type default)
			)
			(layer "F.SilkS")
		)
		(fp_line
			(start 1.651 -1.778)
			(end -1.651 -1.778)
			(stroke
				(width 0.1524)
				(type default)
			)
			(layer "F.SilkS")
		)
		(fp_line
			(start -1.651 1.778)
			(end 1.651 1.778)
			(stroke
				(width 0.1524)
				(type default)
			)
			(layer "F.SilkS")
		)
		(fp_line
			(start -1.651 -1.778)
			(end -1.651 1.778)
			(stroke
				(width 0.1524)
				(type default)
			)
			(layer "F.SilkS")
		)
		(fp_poly
			(pts
				(xy -1.778 1.8796) (xy -1.778 -1.8796) (xy 1.778 -1.8796) (xy 1.778 1.8796)
			)
			(stroke
				(width 0)
				(type default)
			)
			(fill no)
			(layer "F.CrtYd")
		)
		(fp_poly
			(pts
				(xy -1.778 1.8796) (xy -1.778 -1.8796) (xy 1.778 -1.8796) (xy 1.778 1.8796)
			)
			(stroke
				(width 0)
				(type default)
			)
			(fill no)
			(layer "F.Fab")
		)
		(pad "D" smd custom
			(at 0 -0.9525 180)
			(size 0.1905 0.1905)
			(layers "F.Cu" "F.Mask" "F.Paste")
			(net "SCC_A_FULL_PWR_EN_12V")
			(options
				(clearance outline)
				(anchor circle)
			)
			(primitives
				(gr_poly
					(pts
						(arc
							(start -0.1778 0.5715)
							(mid -0.321484 0.511984)
							(end -0.381 0.3683)
						)
						(arc
							(start -0.381 -0.3683)
							(mid -0.321484 -0.511984)
							(end -0.1778 -0.5715)
						)
						(arc
							(start 0.1778 -0.5715)
							(mid 0.321484 -0.511984)
							(end 0.381 -0.3683)
						)
						(arc
							(start 0.381 0.3683)
							(mid 0.321484 0.511984)
							(end 0.1778 0.5715)
						)
					)
					(width 0)
					(fill yes)
				)
			)
		)
		(pad "G" smd custom
			(at -0.98425 0.9525 180)
			(size 0.1905 0.1905)
			(layers "F.Cu" "F.Mask" "F.Paste")
			(net "SCC_A_FULL_PWR_EN")
			(options
				(clearance outline)
				(anchor circle)
			)
			(primitives
				(gr_poly
					(pts
						(arc
							(start -0.1778 0.5715)
							(mid -0.321484 0.511984)
							(end -0.381 0.3683)
						)
						(arc
							(start -0.381 -0.3683)
							(mid -0.321484 -0.511984)
							(end -0.1778 -0.5715)
						)
						(arc
							(start 0.1778 -0.5715)
							(mid 0.321484 -0.511984)
							(end 0.381 -0.3683)
						)
						(arc
							(start 0.381 0.3683)
							(mid 0.321484 0.511984)
							(end 0.1778 0.5715)
						)
					)
					(width 0)
					(fill yes)
				)
			)
		)
		(pad "S" smd custom
			(at 0.98425 0.9525 180)
			(size 0.1905 0.1905)
			(layers "F.Cu" "F.Mask" "F.Paste")
			(net "GND")
			(options
				(clearance outline)
				(anchor circle)
			)
			(primitives
				(gr_poly
					(pts
						(arc
							(start -0.1778 0.5715)
							(mid -0.321484 0.511984)
							(end -0.381 0.3683)
						)
						(arc
							(start -0.381 -0.3683)
							(mid -0.321484 -0.511984)
							(end -0.1778 -0.5715)
						)
						(arc
							(start 0.1778 -0.5715)
							(mid 0.321484 -0.511984)
							(end 0.381 -0.3683)
						)
						(arc
							(start 0.381 0.3683)
							(mid 0.321484 0.511984)
							(end 0.1778 0.5715)
						)
					)
					(width 0)
					(fill yes)
				)
			)
		)
	)
	(footprint ""
		(layer "F.Cu")
		(at 48.694848 -127.254)
		(property "Reference" "R286"
			(at 0 0 0)
			(layer "F.SilkS")
			(hide yes)
			(effects
				(font
					(size 1.27 1.27)
				)
			)
		)
		(property "Value" "130R3F-GP"
			(at -0.0254 -2.5146 0)
			(unlocked yes)
			(layer "F.Fab")
			(hide yes)
			(effects
				(font
					(size 1.016 1.016)
					(thickness 0.1524)
				)
			)
		)
		(property "Device Type" "R603H22"
			(at -0.0254 -4.0386 0)
			(unlocked yes)
			(layer "F.Fab")
			(hide yes)
			(effects
				(font
					(size 1.016 1.016)
					(thickness 0.1524)
				)
			)
		)
		(duplicate_pad_numbers_are_jumpers no)
		(fp_line
			(start -0.4826 0)
			(end -0.2032 0)
			(stroke
				(width 0.2032)
				(type default)
			)
			(layer "F.SilkS")
		)
		(fp_line
			(start 0.2032 0)
			(end 0.4826 0)
			(stroke
				(width 0.2032)
				(type default)
			)
			(layer "F.SilkS")
		)
		(fp_rect
			(start -0.5842 1.3335)
			(end 0.5842 -1.3335)
			(stroke
				(width 0)
				(type default)
			)
			(fill no)
			(layer "F.CrtYd")
		)
		(fp_rect
			(start -0.5842 1.3335)
			(end 0.5842 -1.3335)
			(stroke
				(width 0)
				(type default)
			)
			(fill no)
			(layer "F.Fab")
		)
		(pad "1" smd custom
			(at 0 -0.762)
			(size 0.2159 0.2159)
			(layers "F.Cu" "F.Mask" "F.Paste")
			(net "P5V_A_1")
			(options
				(clearance outline)
				(anchor circle)
			)
			(primitives
				(gr_poly
					(pts
						(arc
							(start -0.3302 -0.4318)
							(mid -0.402042 -0.402042)
							(end -0.4318 -0.3302)
						)
						(arc
							(start -0.4318 0.3302)
							(mid -0.402042 0.402042)
							(end -0.3302 0.4318)
						)
						(arc
							(start 0.3302 0.4318)
							(mid 0.402042 0.402042)
							(end 0.4318 0.3302)
						)
						(arc
							(start 0.4318 -0.3302)
							(mid 0.402042 -0.402042)
							(end 0.3302 -0.4318)
						)
					)
					(width 0)
					(fill yes)
				)
			)
		)
		(pad "2" smd custom
			(at 0 0.762)
			(size 0.2159 0.2159)
			(layers "F.Cu" "F.Mask" "F.Paste")
			(net "FLT_HDD13")
			(options
				(clearance outline)
				(anchor circle)
			)
			(primitives
				(gr_poly
					(pts
						(arc
							(start -0.3302 -0.4318)
							(mid -0.402042 -0.402042)
							(end -0.4318 -0.3302)
						)
						(arc
							(start -0.4318 0.3302)
							(mid -0.402042 0.402042)
							(end -0.3302 0.4318)
						)
						(arc
							(start 0.3302 0.4318)
							(mid 0.402042 0.402042)
							(end 0.4318 0.3302)
						)
						(arc
							(start 0.4318 -0.3302)
							(mid 0.402042 -0.402042)
							(end 0.3302 -0.4318)
						)
					)
					(width 0)
					(fill yes)
				)
			)
		)
	)
	(footprint ""
		(layer "F.Cu")
		(at 51.599846 -176.000918 -90)
		(property "Reference" "C210"
			(at 0 0 270)
			(layer "F.SilkS")
			(hide yes)
			(effects
				(font
					(size 1.27 1.27)
				)
			)
		)
		(property "Value" "SC10U16V6KX-2GP"
			(at -0.0762 -5.1308 270)
			(unlocked yes)
			(layer "F.Fab")
			(hide yes)
			(effects
				(font
					(size 1.016 1.016)
					(thickness 0.1524)
				)
			)
		)
		(property "Device Type" "C1206H71"
			(at -0.127 -6.6548 270)
			(unlocked yes)
			(layer "F.Fab")
			(hide yes)
			(effects
				(font
					(size 1.016 1.016)
					(thickness 0.1524)
				)
			)
		)
		(duplicate_pad_numbers_are_jumpers no)
		(fp_line
			(start -1.016 2.2352)
			(end -1.016 0.8382)
			(stroke
				(width 0.1524)
				(type default)
			)
			(layer "F.SilkS")
		)
		(fp_line
			(start 1.016 2.2352)
			(end -1.016 2.2352)
			(stroke
				(width 0.1524)
				(type default)
			)
			(layer "F.SilkS")
		)
		(fp_line
			(start 1.016 0.8382)
			(end 1.016 2.2352)
			(stroke
				(width 0.1524)
				(type default)
			)
			(layer "F.SilkS")
		)
		(fp_line
			(start -1.016 -0.8382)
			(end -1.016 -2.2352)
			(stroke
				(width 0.1524)
				(type default)
			)
			(layer "F.SilkS")
		)
		(fp_line
			(start -1.016 -2.2352)
			(end 1.016 -2.2352)
			(stroke
				(width 0.1524)
				(type default)
			)
			(layer "F.SilkS")
		)
		(fp_line
			(start 1.016 -2.2352)
			(end 1.016 -0.8382)
			(stroke
				(width 0.1524)
				(type default)
			)
			(layer "F.SilkS")
		)
		(fp_rect
			(start -1.0922 2.3114)
			(end 1.0922 -2.3114)
			(stroke
				(width 0)
				(type default)
			)
			(fill no)
			(layer "F.CrtYd")
		)
		(fp_poly
			(pts
				(xy 1.0922 -2.3114) (xy 1.0922 2.3114) (xy -1.0922 2.3114) (xy -1.0922 -2.3114)
			)
			(stroke
				(width 0)
				(type default)
			)
			(fill no)
			(layer "F.Fab")
		)
		(pad "1" smd rect
			(at 0 -1.397 270)
			(size 1.651 1.27)
			(layers "F.Cu" "F.Mask" "F.Paste")
			(net "P5V_HDD13")
		)
		(pad "2" smd rect
			(at 0 1.397 270)
			(size 1.651 1.27)
			(layers "F.Cu" "F.Mask" "F.Paste")
			(net "GND")
		)
	)
	(footprint ""
		(layer "F.Cu")
		(at 411.539944 -294.438324 180)
		(property "Reference" "R303"
			(at 0 0 180)
			(layer "F.SilkS")
			(hide yes)
			(effects
				(font
					(size 1.27 1.27)
				)
			)
		)
		(property "Value" "130R3F-GP"
			(at -0.0254 -2.5146 180)
			(unlocked yes)
			(layer "F.Fab")
			(hide yes)
			(effects
				(font
					(size 1.016 1.016)
					(thickness 0.1524)
				)
			)
		)
		(property "Device Type" "R603H22"
			(at -0.0254 -4.0386 180)
			(unlocked yes)
			(layer "F.Fab")
			(hide yes)
			(effects
				(font
					(size 1.016 1.016)
					(thickness 0.1524)
				)
			)
		)
		(duplicate_pad_numbers_are_jumpers no)
		(fp_line
			(start 0.2032 0)
			(end 0.4826 0)
			(stroke
				(width 0.2032)
				(type default)
			)
			(layer "F.SilkS")
		)
		(fp_line
			(start -0.4826 0)
			(end -0.2032 0)
			(stroke
				(width 0.2032)
				(type default)
			)
			(layer "F.SilkS")
		)
		(fp_rect
			(start -0.5842 1.3335)
			(end 0.5842 -1.3335)
			(stroke
				(width 0)
				(type default)
			)
			(fill no)
			(layer "F.CrtYd")
		)
		(fp_rect
			(start -0.5842 1.3335)
			(end 0.5842 -1.3335)
			(stroke
				(width 0)
				(type default)
			)
			(fill no)
			(layer "F.Fab")
		)
		(pad "1" smd custom
			(at 0 -0.762 180)
			(size 0.2159 0.2159)
			(layers "F.Cu" "F.Mask" "F.Paste")
			(net "P5V_B")
			(options
				(clearance outline)
				(anchor circle)
			)
			(primitives
				(gr_poly
					(pts
						(arc
							(start -0.3302 -0.4318)
							(mid -0.402042 -0.402042)
							(end -0.4318 -0.3302)
						)
						(arc
							(start -0.4318 0.3302)
							(mid -0.402042 0.402042)
							(end -0.3302 0.4318)
						)
						(arc
							(start 0.3302 0.4318)
							(mid 0.402042 0.402042)
							(end 0.4318 0.3302)
						)
						(arc
							(start 0.4318 -0.3302)
							(mid 0.402042 -0.402042)
							(end 0.3302 -0.4318)
						)
					)
					(width 0)
					(fill yes)
				)
			)
		)
		(pad "2" smd custom
			(at 0 0.762 180)
			(size 0.2159 0.2159)
			(layers "F.Cu" "F.Mask" "F.Paste")
			(net "FLT_HDD33")
			(options
				(clearance outline)
				(anchor circle)
			)
			(primitives
				(gr_poly
					(pts
						(arc
							(start -0.3302 -0.4318)
							(mid -0.402042 -0.402042)
							(end -0.4318 -0.3302)
						)
						(arc
							(start -0.4318 0.3302)
							(mid -0.402042 0.402042)
							(end -0.3302 0.4318)
						)
						(arc
							(start 0.3302 0.4318)
							(mid 0.402042 0.402042)
							(end 0.4318 0.3302)
						)
						(arc
							(start 0.4318 -0.3302)
							(mid 0.402042 -0.402042)
							(end 0.3302 -0.4318)
						)
					)
					(width 0)
					(fill yes)
				)
			)
		)
	)
	(footprint ""
		(layer "F.Cu")
		(at 399.90395 -164.951918 90)
		(property "Reference" "R606"
			(at 0 0 90)
			(layer "F.SilkS")
			(hide yes)
			(effects
				(font
					(size 1.27 1.27)
				)
			)
		)
		(property "Value" "200KR2F-L-GP"
			(at 0.064008 -3.993896 90)
			(unlocked yes)
			(layer "F.Fab")
			(hide yes)
			(effects
				(font
					(size 1.016 1.016)
					(thickness 0.1524)
				)
			)
		)
		(property "Device Type" "R402H16"
			(at 0.064008 -5.517896 90)
			(unlocked yes)
			(layer "F.Fab")
			(hide yes)
			(effects
				(font
					(size 1.016 1.016)
					(thickness 0.1524)
				)
			)
		)
		(duplicate_pad_numbers_are_jumpers no)
		(fp_line
			(start 0.508 -0.9398)
			(end -0.508 -0.9398)
			(stroke
				(width 0.1524)
				(type default)
			)
			(layer "F.SilkS")
		)
		(fp_line
			(start -0.508 -0.9398)
			(end -0.508 0.9398)
			(stroke
				(width 0.1524)
				(type default)
			)
			(layer "F.SilkS")
		)
		(fp_rect
			(start -0.508 0.9398)
			(end 0.508 -0.9398)
			(stroke
				(width 0)
				(type default)
			)
			(fill no)
			(layer "F.CrtYd")
		)
		(fp_rect
			(start -0.508 0.9398)
			(end 0.508 -0.9398)
			(stroke
				(width 0)
				(type default)
			)
			(fill no)
			(layer "F.Fab")
		)
		(pad "1" smd custom
			(at 0 -0.4445 90)
			(size 0.1397 0.1397)
			(layers "F.Cu" "F.Mask" "F.Paste")
			(net "SW_HDD_R20")
			(options
				(clearance outline)
				(anchor circle)
			)
			(primitives
				(gr_poly
					(pts
						(arc
							(start -0.1778 -0.2794)
							(mid -0.249642 -0.249642)
							(end -0.2794 -0.1778)
						)
						(arc
							(start -0.2794 0.1778)
							(mid -0.249642 0.249642)
							(end -0.1778 0.2794)
						)
						(arc
							(start 0.1778 0.2794)
							(mid 0.249642 0.249642)
							(end 0.2794 0.1778)
						)
						(arc
							(start 0.2794 -0.1778)
							(mid 0.249642 -0.249642)
							(end 0.1778 -0.2794)
						)
					)
					(width 0)
					(fill yes)
				)
			)
		)
		(pad "2" smd custom
			(at 0 0.4445 90)
			(size 0.1397 0.1397)
			(layers "F.Cu" "F.Mask" "F.Paste")
			(net "SW_HDD_N20")
			(options
				(clearance outline)
				(anchor circle)
			)
			(primitives
				(gr_poly
					(pts
						(arc
							(start -0.1778 -0.2794)
							(mid -0.249642 -0.249642)
							(end -0.2794 -0.1778)
						)
						(arc
							(start -0.2794 0.1778)
							(mid -0.249642 0.249642)
							(end -0.1778 0.2794)
						)
						(arc
							(start 0.1778 0.2794)
							(mid 0.249642 0.249642)
							(end 0.2794 0.1778)
						)
						(arc
							(start 0.2794 -0.1778)
							(mid 0.249642 -0.249642)
							(end 0.1778 -0.2794)
						)
					)
					(width 0)
					(fill yes)
				)
			)
		)
	)
	(footprint ""
		(layer "F.Cu")
		(at 67.243706 -187.443872)
		(property "Reference" "R461"
			(at 0 0 0)
			(layer "F.SilkS")
			(hide yes)
			(effects
				(font
					(size 1.27 1.27)
				)
			)
		)
		(property "Value" "4K7R2J-2-GP"
			(at 0.064008 -3.993896 0)
			(unlocked yes)
			(layer "F.Fab")
			(hide yes)
			(effects
				(font
					(size 1.016 1.016)
					(thickness 0.1524)
				)
			)
		)
		(property "Device Type" "R402H16"
			(at 0.064008 -5.517896 0)
			(unlocked yes)
			(layer "F.Fab")
			(hide yes)
			(effects
				(font
					(size 1.016 1.016)
					(thickness 0.1524)
				)
			)
		)
		(duplicate_pad_numbers_are_jumpers no)
		(fp_line
			(start -0.508 -0.9398)
			(end -0.508 0.9398)
			(stroke
				(width 0.1524)
				(type default)
			)
			(layer "F.SilkS")
		)
		(fp_line
			(start 0.508 -0.9398)
			(end -0.508 -0.9398)
			(stroke
				(width 0.1524)
				(type default)
			)
			(layer "F.SilkS")
		)
		(fp_rect
			(start -0.508 0.9398)
			(end 0.508 -0.9398)
			(stroke
				(width 0)
				(type default)
			)
			(fill no)
			(layer "F.CrtYd")
		)
		(fp_rect
			(start -0.508 0.9398)
			(end 0.508 -0.9398)
			(stroke
				(width 0)
				(type default)
			)
			(fill no)
			(layer "F.Fab")
		)
		(pad "1" smd custom
			(at 0 -0.4445)
			(size 0.1397 0.1397)
			(layers "F.Cu" "F.Mask" "F.Paste")
			(net "DRIVE_A_2_FLT_LED")
			(options
				(clearance outline)
				(anchor circle)
			)
			(primitives
				(gr_poly
					(pts
						(arc
							(start -0.1778 -0.2794)
							(mid -0.249642 -0.249642)
							(end -0.2794 -0.1778)
						)
						(arc
							(start -0.2794 0.1778)
							(mid -0.249642 0.249642)
							(end -0.1778 0.2794)
						)
						(arc
							(start 0.1778 0.2794)
							(mid 0.249642 0.249642)
							(end 0.2794 0.1778)
						)
						(arc
							(start 0.2794 -0.1778)
							(mid 0.249642 -0.249642)
							(end 0.1778 -0.2794)
						)
					)
					(width 0)
					(fill yes)
				)
			)
		)
		(pad "2" smd custom
			(at 0 0.4445)
			(size 0.1397 0.1397)
			(layers "F.Cu" "F.Mask" "F.Paste")
			(net "GND")
			(options
				(clearance outline)
				(anchor circle)
			)
			(primitives
				(gr_poly
					(pts
						(arc
							(start -0.1778 -0.2794)
							(mid -0.249642 -0.249642)
							(end -0.2794 -0.1778)
						)
						(arc
							(start -0.2794 0.1778)
							(mid -0.249642 0.249642)
							(end -0.1778 0.2794)
						)
						(arc
							(start 0.1778 0.2794)
							(mid 0.249642 0.249642)
							(end 0.2794 0.1778)
						)
						(arc
							(start 0.2794 -0.1778)
							(mid 0.249642 -0.249642)
							(end 0.1778 -0.2794)
						)
					)
					(width 0)
					(fill yes)
				)
			)
		)
	)
	(footprint ""
		(layer "F.Cu")
		(at 190.213488 -159.219392 90)
		(property "Reference" "C259"
			(at 0 0 90)
			(layer "F.SilkS")
			(hide yes)
			(effects
				(font
					(size 1.27 1.27)
				)
			)
		)
		(property "Value" "SCD01U16V1KX-GP"
			(at -2.8321 -1.7399 90)
			(unlocked yes)
			(layer "F.Fab")
			(hide yes)
			(effects
				(font
					(size 1.016 1.016)
					(thickness 0.1524)
				)
			)
		)
		(property "Device Type" "C0201H13"
			(at -2.8321 -3.2639 90)
			(unlocked yes)
			(layer "F.Fab")
			(hide yes)
			(effects
				(font
					(size 1.016 1.016)
					(thickness 0.1524)
				)
			)
		)
		(duplicate_pad_numbers_are_jumpers no)
		(fp_rect
			(start -0.2794 0.6477)
			(end 0.2794 -0.6477)
			(stroke
				(width 0)
				(type default)
			)
			(fill no)
			(layer "F.CrtYd")
		)
		(fp_rect
			(start -0.2794 0.6477)
			(end 0.2794 -0.6477)
			(stroke
				(width 0)
				(type default)
			)
			(fill no)
			(layer "F.Fab")
		)
		(pad "1" smd custom
			(at 0 -0.2794 90)
			(size 0.0762 0.0762)
			(layers "F.Cu" "F.Mask" "F.Paste")
			(net "SAS_HDD_RX_N17")
			(options
				(clearance outline)
				(anchor circle)
			)
			(primitives
				(gr_poly
					(pts
						(arc
							(start 0.1524 -0.127)
							(mid 0.137521 -0.162921)
							(end 0.1016 -0.1778)
						)
						(arc
							(start -0.1016 -0.1778)
							(mid -0.137521 -0.162921)
							(end -0.1524 -0.127)
						)
						(arc
							(start -0.1524 0.127)
							(mid -0.137521 0.162921)
							(end -0.1016 0.1778)
						)
						(arc
							(start 0.1016 0.1778)
							(mid 0.137521 0.162921)
							(end 0.1524 0.127)
						)
					)
					(width 0)
					(fill yes)
				)
			)
		)
		(pad "2" smd custom
			(at 0 0.2794 90)
			(size 0.0762 0.0762)
			(layers "F.Cu" "F.Mask" "F.Paste")
			(net "PHY_SCC_A_TO_DRV_A_17_DN")
			(options
				(clearance outline)
				(anchor circle)
			)
			(primitives
				(gr_poly
					(pts
						(arc
							(start 0.1524 -0.127)
							(mid 0.137521 -0.162921)
							(end 0.1016 -0.1778)
						)
						(arc
							(start -0.1016 -0.1778)
							(mid -0.137521 -0.162921)
							(end -0.1524 -0.127)
						)
						(arc
							(start -0.1524 0.127)
							(mid -0.137521 0.162921)
							(end -0.1016 0.1778)
						)
						(arc
							(start 0.1016 0.1778)
							(mid 0.137521 0.162921)
							(end 0.1524 0.127)
						)
					)
					(width 0)
					(fill yes)
				)
			)
		)
	)
)
